(kicad_pcb
	(version 20241229)
	(generator "pcbnew")
	(generator_version "9.0")
	(general
		(thickness 1.61)
		(legacy_teardrops no)
	)
	(paper "A3")
	(title_block
		(title "SO-DIMM DDR5 Tester")
		(date "2025-11-26")
		(rev "1.3.0")
		(comment 9 "footprints 437-442 of 627")
	)
	(layers
		(0 "F.Cu" signal)
		(4 "In1.Cu" power)
		(6 "In2.Cu" mixed)
		(8 "In3.Cu" power)
		(10 "In4.Cu" mixed)
		(12 "In5.Cu" power)
		(14 "In6.Cu" mixed)
		(16 "In7.Cu" power)
		(18 "In8.Cu" power)
		(20 "In9.Cu" mixed)
		(22 "In10.Cu" power)
		(2 "B.Cu" signal)
		(9 "F.Adhes" user "F.Adhesive")
		(11 "B.Adhes" user "B.Adhesive")
		(13 "F.Paste" user)
		(15 "B.Paste" user)
		(5 "F.SilkS" user "F.Silkscreen")
		(7 "B.SilkS" user "B.Silkscreen")
		(1 "F.Mask" user)
		(3 "B.Mask" user)
		(17 "Dwgs.User" user "User.Drawings")
		(19 "Cmts.User" user "User.Comments")
		(21 "Eco1.User" user "User.Eco1")
		(23 "Eco2.User" user "User.Eco2")
		(25 "Edge.Cuts" user)
		(27 "Margin" user)
		(31 "F.CrtYd" user "F.Courtyard")
		(29 "B.CrtYd" user "B.Courtyard")
		(35 "F.Fab" user)
		(33 "B.Fab" user)
	)
	(footprint "antmicro-footprints:C_0402_1005Metric"
		(layer "B.Cu")
		(at 136.875501 162.301 180)
		(descr "Capacitor SMD 0402 (1005 Metric), square (rectangular) end terminal, IPC_7351 nominal, (Body size source: IPC-SM-782 page 76, https://www.pcb-3d.com/wordpress/wp-content/uploads/ipc-sm-782a_amendment_1_and_2.pdf)")
		(tags "capacitor 0402")
		(property "Reference" "C24"
			(at 0 1.17 0)
			(layer "B.SilkS")
			(hide yes)
			(effects
				(font
					(size 0.7 0.7)
					(thickness 0.15)
				)
				(justify left bottom mirror)
			)
		)
		(property "Value" "C_100n_0402"
			(at 0 -1.169 0)
			(layer "B.Fab")
			(effects
				(font
					(size 0.7 0.7)
					(thickness 0.15)
				)
				(justify left bottom mirror)
			)
		)
		(property "Datasheet" "https://www.murata.com/products/productdetail?partno=GRM155R61H104KE14%23"
			(at 0 0 180)
			(layer "F.Fab")
			(hide yes)
			(effects
				(font
					(size 1.27 1.27)
					(thickness 0.15)
				)
			)
		)
		(property "Author" "Antmicro"
			(at 273.751002 324.602 0)
			(layer "B.Fab")
			(hide yes)
			(effects
				(font
					(size 1 1)
					(thickness 0.15)
				)
				(justify mirror)
			)
		)
		(property "Dielectric" "X5R"
			(at 273.751002 324.602 0)
			(layer "B.Fab")
			(hide yes)
			(effects
				(font
					(size 1 1)
					(thickness 0.15)
				)
				(justify mirror)
			)
		)
		(property "License" "Apache-2.0"
			(at 273.751002 324.602 0)
			(layer "B.Fab")
			(hide yes)
			(effects
				(font
					(size 1 1)
					(thickness 0.15)
				)
				(justify mirror)
			)
		)
		(property "MPN" "GRM155R61H104KE14D"
			(at 273.751002 324.602 0)
			(layer "B.Fab")
			(hide yes)
			(effects
				(font
					(size 1 1)
					(thickness 0.15)
				)
				(justify mirror)
			)
		)
		(property "Manufacturer" "Murata"
			(at 273.751002 324.602 0)
			(layer "B.Fab")
			(hide yes)
			(effects
				(font
					(size 1 1)
					(thickness 0.15)
				)
				(justify mirror)
			)
		)
		(property "Val" "100n"
			(at 273.751002 324.602 0)
			(layer "B.Fab")
			(hide yes)
			(effects
				(font
					(size 1 1)
					(thickness 0.15)
				)
				(justify mirror)
			)
		)
		(property "Voltage" "50V"
			(at 273.751002 324.602 0)
			(layer "B.Fab")
			(hide yes)
			(effects
				(font
					(size 1 1)
					(thickness 0.15)
				)
				(justify mirror)
			)
		)
		(sheetname "/FPGA power/")
		(sheetfile "fpga-power.kicad_sch")
		(attr smd)
		(fp_rect
			(start -0.9656 0.4572)
			(end 0.9652 -0.4828)
			(stroke
				(width 0.05)
				(type solid)
			)
			(fill no)
			(layer "B.CrtYd")
		)
		(fp_line
			(start 0.498 0.25)
			(end 0.498 -0.248)
			(stroke
				(width 0.15)
				(type solid)
			)
			(layer "B.Fab")
		)
		(fp_line
			(start 0.498 -0.248)
			(end -0.5 -0.248)
			(stroke
				(width 0.15)
				(type solid)
			)
			(layer "B.Fab")
		)
		(fp_line
			(start -0.5 0.25)
			(end 0.498 0.25)
			(stroke
				(width 0.15)
				(type solid)
			)
			(layer "B.Fab")
		)
		(fp_line
			(start -0.5 -0.248)
			(end -0.5 0.25)
			(stroke
				(width 0.15)
				(type solid)
			)
			(layer "B.Fab")
		)
		(pad "1" smd roundrect
			(at -0.5 0 90)
			(size 0.6 0.6)
			(layers "B.Cu" "B.Mask" "B.Paste")
			(roundrect_rratio 0.25)
			(net 1 "GND")
			(pintype "passive")
		)
		(pad "2" smd roundrect
			(at 0.498 0 180)
			(size 0.6 0.6)
			(layers "B.Cu" "B.Mask" "B.Paste")
			(roundrect_rratio 0.25)
			(net 206 "+1V1")
			(pintype "passive")
		)
	)
	(footprint "antmicro-footprints:C_0402_1005Metric"
		(layer "B.Cu")
		(at 196.55 141.25 180)
		(descr "Capacitor SMD 0402")
		(tags "capacitor SMD 0402")
		(property "Reference" "C203"
			(at 0 0.699 0)
			(layer "B.SilkS")
			(hide yes)
			(effects
				(font
					(size 0.7 0.7)
					(thickness 0.15)
				)
				(justify left bottom mirror)
			)
		)
		(property "Value" "C_100n_0402"
			(at -1.022927 -2.155213 0)
			(layer "B.Fab")
			(effects
				(font
					(size 0.7 0.7)
					(thickness 0.15)
				)
				(justify left bottom mirror)
			)
		)
		(property "Datasheet" "https://www.murata.com/products/productdetail?partno=GRM155R61H104KE14%23"
			(at 0 0 180)
			(layer "F.Fab")
			(hide yes)
			(effects
				(font
					(size 1.27 1.27)
					(thickness 0.15)
				)
			)
		)
		(property "Author" "Antmicro"
			(at 393.1 282.5 0)
			(layer "B.Fab")
			(hide yes)
			(effects
				(font
					(size 1 1)
					(thickness 0.15)
				)
				(justify mirror)
			)
		)
		(property "Dielectric" "X5R"
			(at 393.1 282.5 0)
			(layer "B.Fab")
			(hide yes)
			(effects
				(font
					(size 1 1)
					(thickness 0.15)
				)
				(justify mirror)
			)
		)
		(property "License" "Apache-2.0"
			(at 393.1 282.5 0)
			(layer "B.Fab")
			(hide yes)
			(effects
				(font
					(size 1 1)
					(thickness 0.15)
				)
				(justify mirror)
			)
		)
		(property "MPN" "GRM155R61H104KE14D"
			(at 393.1 282.5 0)
			(layer "B.Fab")
			(hide yes)
			(effects
				(font
					(size 1 1)
					(thickness 0.15)
				)
				(justify mirror)
			)
		)
		(property "Manufacturer" "Murata"
			(at 393.1 282.5 0)
			(layer "B.Fab")
			(hide yes)
			(effects
				(font
					(size 1 1)
					(thickness 0.15)
				)
				(justify mirror)
			)
		)
		(property "Val" "100n"
			(at 393.1 282.5 0)
			(layer "B.Fab")
			(hide yes)
			(effects
				(font
					(size 1 1)
					(thickness 0.15)
				)
				(justify mirror)
			)
		)
		(property "Voltage" "50V"
			(at 393.1 282.5 0)
			(layer "B.Fab")
			(hide yes)
			(effects
				(font
					(size 1 1)
					(thickness 0.15)
				)
				(justify mirror)
			)
		)
		(sheetname "/Supply/")
		(sheetfile "supply.kicad_sch")
		(attr smd)
		(fp_rect
			(start -0.9659 0.481258)
			(end 0.9649 -0.458742)
			(stroke
				(width 0.05)
				(type solid)
			)
			(fill no)
			(layer "B.CrtYd")
		)
		(fp_line
			(start 0.499 0.25)
			(end 0.499 -0.248)
			(stroke
				(width 0.15)
				(type solid)
			)
			(layer "B.Fab")
		)
		(fp_line
			(start 0.499 -0.248)
			(end -0.499 -0.248)
			(stroke
				(width 0.15)
				(type solid)
			)
			(layer "B.Fab")
		)
		(fp_line
			(start -0.499 0.25)
			(end 0.499 0.25)
			(stroke
				(width 0.15)
				(type solid)
			)
			(layer "B.Fab")
		)
		(fp_line
			(start -0.499 -0.248)
			(end -0.499 0.25)
			(stroke
				(width 0.15)
				(type solid)
			)
			(layer "B.Fab")
		)
		(pad "1" smd roundrect
			(at -0.484 0 180)
			(size 0.59 0.64)
			(layers "B.Cu" "B.Mask" "B.Paste")
			(roundrect_rratio 0.25)
			(net 41 "+3V3_AON")
			(pintype "passive")
		)
		(pad "2" smd roundrect
			(at 0.484 0 180)
			(size 0.59 0.64)
			(layers "B.Cu" "B.Mask" "B.Paste")
			(roundrect_rratio 0.25)
			(net 1 "GND")
			(pintype "passive")
		)
	)
	(footprint "antmicro-footprints:R_0402_1005Metric"
		(layer "B.Cu")
		(at 137 142.4 -90)
		(descr "Resistor SMD 0402")
		(tags "resistor SMD 0402")
		(property "Reference" "R23"
			(at -3.044968 -0.354606 90)
			(layer "B.SilkS")
			(effects
				(font
					(size 0.7 0.7)
					(thickness 0.15)
				)
				(justify left bottom mirror)
			)
		)
		(property "Value" "R_47k_0402"
			(at -1.011843 -1.772047 90)
			(layer "B.Fab")
			(effects
				(font
					(size 0.7 0.7)
					(thickness 0.15)
				)
				(justify left bottom mirror)
			)
		)
		(property "Datasheet" "https://www.bourns.com/docs/product-datasheets/cr.pdf"
			(at 0 0 270)
			(layer "F.Fab")
			(hide yes)
			(effects
				(font
					(size 1.27 1.27)
					(thickness 0.15)
				)
			)
		)
		(property "Author" "Antmicro"
			(at -5.4 279.4 0)
			(layer "B.Fab")
			(hide yes)
			(effects
				(font
					(size 1 1)
					(thickness 0.15)
				)
				(justify mirror)
			)
		)
		(property "License" "Apache-2.0"
			(at -5.4 279.4 0)
			(layer "B.Fab")
			(hide yes)
			(effects
				(font
					(size 1 1)
					(thickness 0.15)
				)
				(justify mirror)
			)
		)
		(property "MPN" "CR0402-FX-4702GLF"
			(at -5.4 279.4 0)
			(layer "B.Fab")
			(hide yes)
			(effects
				(font
					(size 1 1)
					(thickness 0.15)
				)
				(justify mirror)
			)
		)
		(property "Manufacturer" "Bourns"
			(at -5.4 279.4 0)
			(layer "B.Fab")
			(hide yes)
			(effects
				(font
					(size 1 1)
					(thickness 0.15)
				)
				(justify mirror)
			)
		)
		(property "Tolerance" "1%"
			(at -5.4 279.4 0)
			(layer "B.Fab")
			(hide yes)
			(effects
				(font
					(size 1 1)
					(thickness 0.15)
				)
				(justify mirror)
			)
		)
		(property "Val" "47k"
			(at -5.4 279.4 0)
			(layer "B.Fab")
			(hide yes)
			(effects
				(font
					(size 1 1)
					(thickness 0.15)
				)
				(justify mirror)
			)
		)
		(sheetname "/DDR5 SODIMM/")
		(sheetfile "ddr5-sodimm.kicad_sch")
		(attr smd)
		(fp_rect
			(start -0.93 0.47)
			(end 0.93 -0.47)
			(stroke
				(width 0.05)
				(type solid)
			)
			(fill no)
			(layer "B.CrtYd")
		)
		(fp_rect
			(start -0.5 0.25)
			(end 0.5 -0.25)
			(stroke
				(width 0.15)
				(type solid)
			)
			(fill no)
			(layer "B.Fab")
		)
		(pad "1" smd roundrect
			(at -0.485 0 270)
			(size 0.59 0.64)
			(layers "B.Cu" "B.Mask" "B.Paste")
			(roundrect_rratio 0.25)
			(net 172 "/DDR5 SODIMM/VSS_DET2")
			(pintype "passive")
		)
		(pad "2" smd roundrect
			(at 0.485 0 270)
			(size 0.59 0.64)
			(layers "B.Cu" "B.Mask" "B.Paste")
			(roundrect_rratio 0.25)
			(net 200 "+3V3")
			(pintype "passive")
		)
	)
	(footprint "antmicro-footprints:C_0402_1005Metric"
		(layer "B.Cu")
		(at 126.375501 181.801 -90)
		(descr "Capacitor SMD 0402 (1005 Metric), square (rectangular) end terminal, IPC_7351 nominal, (Body size source: IPC-SM-782 page 76, https://www.pcb-3d.com/wordpress/wp-content/uploads/ipc-sm-782a_amendment_1_and_2.pdf)")
		(tags "capacitor 0402")
		(property "Reference" "C36"
			(at 0 1.17 90)
			(layer "B.SilkS")
			(hide yes)
			(effects
				(font
					(size 0.7 0.7)
					(thickness 0.15)
				)
				(justify left bottom mirror)
			)
		)
		(property "Value" "C_100n_0402"
			(at 0 -1.169 90)
			(layer "B.Fab")
			(effects
				(font
					(size 0.7 0.7)
					(thickness 0.15)
				)
				(justify left bottom mirror)
			)
		)
		(property "Datasheet" "https://www.murata.com/products/productdetail?partno=GRM155R61H104KE14%23"
			(at 0 0 270)
			(layer "F.Fab")
			(hide yes)
			(effects
				(font
					(size 1.27 1.27)
					(thickness 0.15)
				)
			)
		)
		(property "Author" "Antmicro"
			(at -55.425499 308.176501 0)
			(layer "B.Fab")
			(hide yes)
			(effects
				(font
					(size 1 1)
					(thickness 0.15)
				)
				(justify mirror)
			)
		)
		(property "Dielectric" "X5R"
			(at -55.425499 308.176501 0)
			(layer "B.Fab")
			(hide yes)
			(effects
				(font
					(size 1 1)
					(thickness 0.15)
				)
				(justify mirror)
			)
		)
		(property "License" "Apache-2.0"
			(at -55.425499 308.176501 0)
			(layer "B.Fab")
			(hide yes)
			(effects
				(font
					(size 1 1)
					(thickness 0.15)
				)
				(justify mirror)
			)
		)
		(property "MPN" "GRM155R61H104KE14D"
			(at -55.425499 308.176501 0)
			(layer "B.Fab")
			(hide yes)
			(effects
				(font
					(size 1 1)
					(thickness 0.15)
				)
				(justify mirror)
			)
		)
		(property "Manufacturer" "Murata"
			(at -55.425499 308.176501 0)
			(layer "B.Fab")
			(hide yes)
			(effects
				(font
					(size 1 1)
					(thickness 0.15)
				)
				(justify mirror)
			)
		)
		(property "Val" "100n"
			(at -55.425499 308.176501 0)
			(layer "B.Fab")
			(hide yes)
			(effects
				(font
					(size 1 1)
					(thickness 0.15)
				)
				(justify mirror)
			)
		)
		(property "Voltage" "50V"
			(at -55.425499 308.176501 0)
			(layer "B.Fab")
			(hide yes)
			(effects
				(font
					(size 1 1)
					(thickness 0.15)
				)
				(justify mirror)
			)
		)
		(sheetname "/FPGA power/")
		(sheetfile "fpga-power.kicad_sch")
		(attr smd)
		(fp_rect
			(start -0.9656 0.4572)
			(end 0.9652 -0.4828)
			(stroke
				(width 0.05)
				(type solid)
			)
			(fill no)
			(layer "B.CrtYd")
		)
		(fp_line
			(start -0.5 0.25)
			(end 0.498 0.25)
			(stroke
				(width 0.15)
				(type solid)
			)
			(layer "B.Fab")
		)
		(fp_line
			(start 0.498 0.25)
			(end 0.498 -0.248)
			(stroke
				(width 0.15)
				(type solid)
			)
			(layer "B.Fab")
		)
		(fp_line
			(start -0.5 -0.248)
			(end -0.5 0.25)
			(stroke
				(width 0.15)
				(type solid)
			)
			(layer "B.Fab")
		)
		(fp_line
			(start 0.498 -0.248)
			(end -0.5 -0.248)
			(stroke
				(width 0.15)
				(type solid)
			)
			(layer "B.Fab")
		)
		(pad "1" smd roundrect
			(at -0.5 0 180)
			(size 0.6 0.6)
			(layers "B.Cu" "B.Mask" "B.Paste")
			(roundrect_rratio 0.25)
			(net 1 "GND")
			(pintype "passive")
		)
		(pad "2" smd roundrect
			(at 0.498 0 270)
			(size 0.6 0.6)
			(layers "B.Cu" "B.Mask" "B.Paste")
			(roundrect_rratio 0.25)
			(net 200 "+3V3")
			(pintype "passive")
		)
	)
	(footprint "antmicro-footprints:TP_SMD_1mm"
		(layer "B.Cu")
		(at 181.066 147.52 180)
		(property "Reference" "TP66"
			(at -1.244 0.73 0)
			(layer "B.SilkS")
			(effects
				(font
					(size 0.7 0.7)
					(thickness 0.15)
				)
				(justify left bottom mirror)
			)
		)
		(property "Value" "TP_1mm_SMD"
			(at 0 -1.4 0)
			(layer "B.Fab")
			(effects
				(font
					(size 0.7 0.7)
					(thickness 0.15)
				)
				(justify left bottom mirror)
			)
		)
		(property "MPN" ""
			(at 0 0 0)
			(unlocked yes)
			(layer "B.Fab")
			(hide yes)
			(effects
				(font
					(size 1 1)
					(thickness 0.15)
				)
				(justify mirror)
			)
		)
		(property "Manufacturer" ""
			(at 0 0 0)
			(unlocked yes)
			(layer "B.Fab")
			(hide yes)
			(effects
				(font
					(size 1 1)
					(thickness 0.15)
				)
				(justify mirror)
			)
		)
		(property "Author" "Antmicro"
			(at 0 0 0)
			(unlocked yes)
			(layer "B.Fab")
			(hide yes)
			(effects
				(font
					(size 1 1)
					(thickness 0.15)
				)
				(justify mirror)
			)
		)
		(property "License" "Apache-2.0"
			(at 0 0 0)
			(unlocked yes)
			(layer "B.Fab")
			(hide yes)
			(effects
				(font
					(size 1 1)
					(thickness 0.15)
				)
				(justify mirror)
			)
		)
		(sheetname "/Supply/")
		(sheetfile "supply.kicad_sch")
		(attr exclude_from_pos_files)
		(fp_circle
			(center 0 0)
			(end 0.6 0)
			(stroke
				(width 0.05)
				(type default)
			)
			(fill no)
			(layer "B.CrtYd")
		)
		(fp_text user "${REFERENCE}"
			(at -0.5 -2.8 0)
			(layer "B.Fab")
			(effects
				(font
					(size 0.7 0.7)
					(thickness 0.15)
				)
				(justify left bottom mirror)
			)
		)
		(fp_text user "Author: Antmicro"
			(at -0.5 -4 0)
			(layer "B.Fab")
			(effects
				(font
					(size 0.7 0.7)
					(thickness 0.15)
				)
				(justify left bottom mirror)
			)
		)
		(fp_text user "License: Apache-2.0"
			(at -0.5 -5.2 0)
			(layer "B.Fab")
			(effects
				(font
					(size 0.7 0.7)
					(thickness 0.15)
				)
				(justify left bottom mirror)
			)
		)
		(pad "1" smd circle
			(at 0 0 180)
			(size 1 1)
			(layers "B.Cu" "B.Mask")
			(net 36 "DAC_VREF")
			(pinfunction "1")
			(pintype "passive")
		)
	)
	(footprint "antmicro-footprints:C_0402_1005Metric"
		(layer "B.Cu")
		(at 130.375501 162.801 -90)
		(descr "Capacitor SMD 0402 (1005 Metric), square (rectangular) end terminal, IPC_7351 nominal, (Body size source: IPC-SM-782 page 76, https://www.pcb-3d.com/wordpress/wp-content/uploads/ipc-sm-782a_amendment_1_and_2.pdf)")
		(tags "capacitor 0402")
		(property "Reference" "C29"
			(at 0 1.17 90)
			(layer "B.SilkS")
			(hide yes)
			(effects
				(font
					(size 0.7 0.7)
					(thickness 0.15)
				)
				(justify left bottom mirror)
			)
		)
		(property "Value" "C_100n_0402"
			(at 0 -1.169 90)
			(layer "B.Fab")
			(effects
				(font
					(size 0.7 0.7)
					(thickness 0.15)
				)
				(justify left bottom mirror)
			)
		)
		(property "Datasheet" "https://www.murata.com/products/productdetail?partno=GRM155R61H104KE14%23"
			(at 0 0 270)
			(layer "F.Fab")
			(hide yes)
			(effects
				(font
					(size 1.27 1.27)
					(thickness 0.15)
				)
			)
		)
		(property "Author" "Antmicro"
			(at -32.425499 293.176501 0)
			(layer "B.Fab")
			(hide yes)
			(effects
				(font
					(size 1 1)
					(thickness 0.15)
				)
				(justify mirror)
			)
		)
		(property "Dielectric" "X5R"
			(at -32.425499 293.176501 0)
			(layer "B.Fab")
			(hide yes)
			(effects
				(font
					(size 1 1)
					(thickness 0.15)
				)
				(justify mirror)
			)
		)
		(property "License" "Apache-2.0"
			(at -32.425499 293.176501 0)
			(layer "B.Fab")
			(hide yes)
			(effects
				(font
					(size 1 1)
					(thickness 0.15)
				)
				(justify mirror)
			)
		)
		(property "MPN" "GRM155R61H104KE14D"
			(at -32.425499 293.176501 0)
			(layer "B.Fab")
			(hide yes)
			(effects
				(font
					(size 1 1)
					(thickness 0.15)
				)
				(justify mirror)
			)
		)
		(property "Manufacturer" "Murata"
			(at -32.425499 293.176501 0)
			(layer "B.Fab")
			(hide yes)
			(effects
				(font
					(size 1 1)
					(thickness 0.15)
				)
				(justify mirror)
			)
		)
		(property "Val" "100n"
			(at -32.425499 293.176501 0)
			(layer "B.Fab")
			(hide yes)
			(effects
				(font
					(size 1 1)
					(thickness 0.15)
				)
				(justify mirror)
			)
		)
		(property "Voltage" "50V"
			(at -32.425499 293.176501 0)
			(layer "B.Fab")
			(hide yes)
			(effects
				(font
					(size 1 1)
					(thickness 0.15)
				)
				(justify mirror)
			)
		)
		(sheetname "/FPGA power/")
		(sheetfile "fpga-power.kicad_sch")
		(attr smd)
		(fp_rect
			(start -0.9656 0.4572)
			(end 0.9652 -0.4828)
			(stroke
				(width 0.05)
				(type solid)
			)
			(fill no)
			(layer "B.CrtYd")
		)
		(fp_line
			(start -0.5 0.25)
			(end 0.498 0.25)
			(stroke
				(width 0.15)
				(type solid)
			)
			(layer "B.Fab")
		)
		(fp_line
			(start 0.498 0.25)
			(end 0.498 -0.248)
			(stroke
				(width 0.15)
				(type solid)
			)
			(layer "B.Fab")
		)
		(fp_line
			(start -0.5 -0.248)
			(end -0.5 0.25)
			(stroke
				(width 0.15)
				(type solid)
			)
			(layer "B.Fab")
		)
		(fp_line
			(start 0.498 -0.248)
			(end -0.5 -0.248)
			(stroke
				(width 0.15)
				(type solid)
			)
			(layer "B.Fab")
		)
		(pad "1" smd roundrect
			(at -0.5 0 180)
			(size 0.6 0.6)
			(layers "B.Cu" "B.Mask" "B.Paste")
			(roundrect_rratio 0.25)
			(net 1 "GND")
			(pintype "passive")
		)
		(pad "2" smd roundrect
			(at 0.498 0 270)
			(size 0.6 0.6)
			(layers "B.Cu" "B.Mask" "B.Paste")
			(roundrect_rratio 0.25)
			(net 200 "+3V3")
			(pintype "passive")
		)
	)
)
